(kicad_pcb
	(version 20260206)
	(generator "pcbnew")
	(generator_version "10.0")
	(general
		(thickness 1.6)
		(legacy_teardrops no)
	)
	(paper "A4")
	(title_block
		(title "Wiwynn_Tioga_Pass_MB.brd")
		(comment 1 "Tioga Pass / footprints 3405-3411 of 4770")
	)
	(layers
		(0 "F.Cu" signal "TOP")
		(4 "In1.Cu" signal "L2GND")
		(6 "In2.Cu" signal "L3")
		(8 "In3.Cu" signal "L4GND")
		(10 "In4.Cu" signal "L5")
		(12 "In5.Cu" signal "L6GND")
		(14 "In6.Cu" signal "L7VCC")
		(16 "In7.Cu" signal "L8VCC")
		(18 "In8.Cu" signal "L9GND")
		(20 "In9.Cu" signal "L10")
		(22 "In10.Cu" signal "L11GND")
		(24 "In11.Cu" signal "L12")
		(26 "In12.Cu" signal "L13GND")
		(2 "B.Cu" signal "BOTTOM")
		(9 "F.Adhes" user "F.Adhesive")
		(11 "B.Adhes" user "B.Adhesive")
		(13 "F.Paste" user "Package Geometry/Pastemask Top")
		(15 "B.Paste" user "Package Geometry/Pastemask Bottom")
		(5 "F.SilkS" user "Ref Des/Silkscreen Top")
		(7 "B.SilkS" user "Ref Des/Silkscreen Bottom")
		(1 "F.Mask" user "Board Geometry/Soldermask Top")
		(3 "B.Mask" user "Board Geometry/Soldermask Bottom")
		(17 "Dwgs.User" user "User.Drawings")
		(19 "Cmts.User" user "User.Comments")
		(21 "Eco1.User" user "User.Eco1")
		(23 "Eco2.User" user "User.Eco2")
		(25 "Edge.Cuts" user "Board Geometry/Outline")
		(27 "Margin" user)
		(31 "F.CrtYd" user "Package Geometry/Place Bound Top")
		(29 "B.CrtYd" user "Package Geometry/Place Bound Bottom")
		(35 "F.Fab" user "Ref Des/Assembly Top")
		(33 "B.Fab" user "Ref Des/Assembly Bottom")
	)
	(footprint ""
		(layer "B.Cu")
		(at 450.215 -150.1394 -90)
		(property "Reference" "R25W176"
			(at 0.8382 -0.67818 270)
			(unlocked yes)
			(layer "B.SilkS")
			(effects
				(font
					(size 0.4064 0.254)
					(thickness 0.1524)
				)
				(justify left mirror)
			)
		)
		(property "Value" ""
			(at 0 0 90)
			(layer "B.Fab")
			(effects
				(font
					(size 1.27 1.27)
				)
				(justify mirror)
			)
		)
		(duplicate_pad_numbers_are_jumpers no)
		(fp_poly
			(pts
				(xy 0.2794 -0.1016) (xy -0.2794 -0.1016) (xy -0.2794 0.9906) (xy 0.2794 0.9906)
			)
			(stroke
				(width 0)
				(type default)
			)
			(fill no)
			(layer "B.CrtYd")
		)
		(fp_line
			(start -0.2794 0.9906)
			(end -0.2794 -0.1016)
			(stroke
				(width 0.1)
				(type default)
			)
			(layer "B.Fab")
		)
		(fp_line
			(start 0.2794 0.9906)
			(end -0.2794 0.9906)
			(stroke
				(width 0.1)
				(type default)
			)
			(layer "B.Fab")
		)
		(fp_line
			(start -0.2794 -0.1016)
			(end 0.2794 -0.1016)
			(stroke
				(width 0.1)
				(type default)
			)
			(layer "B.Fab")
		)
		(fp_line
			(start 0.2794 -0.1016)
			(end 0.2794 0.9906)
			(stroke
				(width 0.1)
				(type default)
			)
			(layer "B.Fab")
		)
		(pad "1" smd rect
			(at 0 0 90)
			(size 0.508 0.508)
			(layers "B.Cu" "B.Mask" "B.Paste")
			(net "PD_GTL2014_6_B2")
		)
		(pad "2" smd rect
			(at 0 0.889 90)
			(size 0.508 0.508)
			(layers "B.Cu" "B.Mask" "B.Paste")
			(net "GND")
		)
		(zone
			(layer "B.Cu")
			(hatch none 0.5)
			(connect_pads
				(clearance 0)
			)
			(min_thickness 0.25)
			(keepout
				(tracks not_allowed)
				(vias allowed)
				(pads allowed)
				(copperpour not_allowed)
				(footprints allowed)
			)
			(placement
				(enabled no)
				(sheetname "")
			)
			(fill
				(thermal_gap 0.5)
				(thermal_bridge_width 0.5)
				(island_removal_mode 0)
			)
			(polygon
				(pts
					(xy 449.58 -149.8854) (xy 449.58 -150.3934) (xy 449.961 -150.3934) (xy 449.961 -149.8854)
				)
			)
		)
		(zone
			(layer "B.Cu")
			(hatch none 0.5)
			(connect_pads
				(clearance 0)
			)
			(min_thickness 0.25)
			(keepout
				(tracks allowed)
				(vias not_allowed)
				(pads allowed)
				(copperpour not_allowed)
				(footprints allowed)
			)
			(placement
				(enabled no)
				(sheetname "")
			)
			(fill
				(thermal_gap 0.5)
				(thermal_bridge_width 0.5)
				(island_removal_mode 0)
			)
			(polygon
				(pts
					(xy 449.961 -149.8854) (xy 449.961 -150.3934) (xy 449.58 -150.3934) (xy 449.58 -149.8854)
				)
			)
		)
	)
	(footprint ""
		(layer "B.Cu")
		(at 492.3536 -133.223 90)
		(property "Reference" "U6W4"
			(at 0.14986 2.621788 90)
			(unlocked yes)
			(layer "B.SilkS")
			(effects
				(font
					(size 1.27 0.964946)
					(thickness 0.000001)
				)
				(justify left mirror)
			)
		)
		(property "Value" ""
			(at 0 0 90)
			(layer "B.Fab")
			(effects
				(font
					(size 1.27 1.27)
				)
				(justify mirror)
			)
		)
		(duplicate_pad_numbers_are_jumpers no)
		(fp_circle
			(center 0.4699 -0.8382)
			(end 0.4699 -0.7112)
			(stroke
				(width 0.254)
				(type default)
			)
			(fill no)
			(layer "B.SilkS")
		)
		(fp_poly
			(pts
				(xy -0.21463 -0.450088) (xy -1.56337 -0.450088) (xy -1.56337 1.75006) (xy -0.21463 1.75006)
			)
			(stroke
				(width 0)
				(type default)
			)
			(fill no)
			(layer "B.CrtYd")
		)
		(fp_line
			(start -0.21463 -0.450088)
			(end -1.56337 -0.450088)
			(stroke
				(width 0.1)
				(type default)
			)
			(layer "B.Fab")
		)
		(fp_line
			(start -1.56337 -0.450088)
			(end -1.56337 1.75006)
			(stroke
				(width 0.1)
				(type default)
			)
			(layer "B.Fab")
		)
		(fp_line
			(start -0.21463 1.75006)
			(end -0.21463 -0.450088)
			(stroke
				(width 0.1)
				(type default)
			)
			(layer "B.Fab")
		)
		(fp_line
			(start -1.56337 1.75006)
			(end -0.21463 1.75006)
			(stroke
				(width 0.1)
				(type default)
			)
			(layer "B.Fab")
		)
		(fp_circle
			(center 0.4699 -0.8382)
			(end 0.4699 -0.7112)
			(stroke
				(width 0.254)
				(type default)
			)
			(fill no)
			(layer "B.Fab")
		)
		(pad "1" smd rect
			(at 0 0 270)
			(size 1.016 0.381)
			(layers "B.Cu" "B.Mask" "B.Paste")
			(net "DEBUG_CARD2_PRSNT")
		)
		(pad "2" smd rect
			(at 0 0.649986 270)
			(size 1.016 0.381)
			(layers "B.Cu" "B.Mask" "B.Paste")
			(net "SPA_MID_DBG2_RX")
		)
		(pad "3" smd rect
			(at 0 1.299972 270)
			(size 1.016 0.381)
			(layers "B.Cu" "B.Mask" "B.Paste")
			(net "GND")
		)
		(pad "4" smd rect
			(at -1.778 1.299972 270)
			(size 1.016 0.381)
			(layers "B.Cu" "B.Mask" "B.Paste")
			(net "SPA_MID_DBG2_RX_BUF")
		)
		(pad "5" smd rect
			(at -1.778 0 270)
			(size 1.016 0.381)
			(layers "B.Cu" "B.Mask" "B.Paste")
			(net "P3V3_STBY")
		)
	)
	(footprint ""
		(layer "B.Cu")
		(at 350.9772 -88.269572 90)
		(property "Reference" "R3N31"
			(at 0 0 90)
			(layer "B.SilkS")
			(hide yes)
			(effects
				(font
					(size 1.27 1.27)
				)
				(justify mirror)
			)
		)
		(property "Value" ""
			(at 0 0 90)
			(layer "B.Fab")
			(effects
				(font
					(size 1.27 1.27)
				)
				(justify mirror)
			)
		)
		(duplicate_pad_numbers_are_jumpers no)
		(fp_poly
			(pts
				(xy 0.2794 -0.1016) (xy -0.2794 -0.1016) (xy -0.2794 0.9906) (xy 0.2794 0.9906)
			)
			(stroke
				(width 0)
				(type default)
			)
			(fill no)
			(layer "B.CrtYd")
		)
		(fp_line
			(start 0.2794 -0.1016)
			(end 0.2794 0.9906)
			(stroke
				(width 0.1)
				(type default)
			)
			(layer "B.Fab")
		)
		(fp_line
			(start -0.2794 -0.1016)
			(end 0.2794 -0.1016)
			(stroke
				(width 0.1)
				(type default)
			)
			(layer "B.Fab")
		)
		(fp_line
			(start 0.2794 0.9906)
			(end -0.2794 0.9906)
			(stroke
				(width 0.1)
				(type default)
			)
			(layer "B.Fab")
		)
		(fp_line
			(start -0.2794 0.9906)
			(end -0.2794 -0.1016)
			(stroke
				(width 0.1)
				(type default)
			)
			(layer "B.Fab")
		)
		(pad "1" smd rect
			(at 0 0 270)
			(size 0.508 0.508)
			(layers "B.Cu" "B.Mask" "B.Paste")
			(net "VR_PVCCIO_CPU0_XADDR1")
		)
		(pad "2" smd rect
			(at 0 0.889 270)
			(size 0.508 0.508)
			(layers "B.Cu" "B.Mask" "B.Paste")
			(net "GND")
		)
		(zone
			(layer "B.Cu")
			(hatch none 0.5)
			(connect_pads
				(clearance 0)
			)
			(min_thickness 0.25)
			(keepout
				(tracks allowed)
				(vias not_allowed)
				(pads allowed)
				(copperpour not_allowed)
				(footprints allowed)
			)
			(placement
				(enabled no)
				(sheetname "")
			)
			(fill
				(thermal_gap 0.5)
				(thermal_bridge_width 0.5)
				(island_removal_mode 0)
			)
			(polygon
				(pts
					(xy 351.2312 -88.523572) (xy 351.2312 -88.015572) (xy 351.6122 -88.015572) (xy 351.6122 -88.523572)
				)
			)
		)
		(zone
			(layer "B.Cu")
			(hatch none 0.5)
			(connect_pads
				(clearance 0)
			)
			(min_thickness 0.25)
			(keepout
				(tracks not_allowed)
				(vias allowed)
				(pads allowed)
				(copperpour not_allowed)
				(footprints allowed)
			)
			(placement
				(enabled no)
				(sheetname "")
			)
			(fill
				(thermal_gap 0.5)
				(thermal_bridge_width 0.5)
				(island_removal_mode 0)
			)
			(polygon
				(pts
					(xy 351.6122 -88.523572) (xy 351.6122 -88.015572) (xy 351.2312 -88.015572) (xy 351.2312 -88.523572)
				)
			)
		)
	)
	(footprint ""
		(layer "B.Cu")
		(at 411.861 -7.4295 180)
		(property "Reference" "R8D41"
			(at 0 0 0)
			(layer "B.SilkS")
			(hide yes)
			(effects
				(font
					(size 1.27 1.27)
				)
				(justify mirror)
			)
		)
		(property "Value" ""
			(at 0 0 0)
			(layer "B.Fab")
			(effects
				(font
					(size 1.27 1.27)
				)
				(justify mirror)
			)
		)
		(duplicate_pad_numbers_are_jumpers no)
		(fp_poly
			(pts
				(xy 0.2794 -0.1016) (xy -0.2794 -0.1016) (xy -0.2794 0.9906) (xy 0.2794 0.9906)
			)
			(stroke
				(width 0)
				(type default)
			)
			(fill no)
			(layer "B.CrtYd")
		)
		(fp_line
			(start 0.2794 0.9906)
			(end -0.2794 0.9906)
			(stroke
				(width 0.1)
				(type default)
			)
			(layer "B.Fab")
		)
		(fp_line
			(start 0.2794 -0.1016)
			(end 0.2794 0.9906)
			(stroke
				(width 0.1)
				(type default)
			)
			(layer "B.Fab")
		)
		(fp_line
			(start -0.2794 0.9906)
			(end -0.2794 -0.1016)
			(stroke
				(width 0.1)
				(type default)
			)
			(layer "B.Fab")
		)
		(fp_line
			(start -0.2794 -0.1016)
			(end 0.2794 -0.1016)
			(stroke
				(width 0.1)
				(type default)
			)
			(layer "B.Fab")
		)
		(pad "1" smd rect
			(at 0 0)
			(size 0.508 0.508)
			(layers "B.Cu" "B.Mask" "B.Paste")
			(net "P3V3_STBY")
		)
		(pad "2" smd rect
			(at 0 0.889)
			(size 0.508 0.508)
			(layers "B.Cu" "B.Mask" "B.Paste")
			(net "PWRGD_P12V_MAIN_R")
		)
		(zone
			(layer "B.Cu")
			(hatch none 0.5)
			(connect_pads
				(clearance 0)
			)
			(min_thickness 0.25)
			(keepout
				(tracks not_allowed)
				(vias allowed)
				(pads allowed)
				(copperpour not_allowed)
				(footprints allowed)
			)
			(placement
				(enabled no)
				(sheetname "")
			)
			(fill
				(thermal_gap 0.5)
				(thermal_bridge_width 0.5)
				(island_removal_mode 0)
			)
			(polygon
				(pts
					(xy 411.607 -8.0645) (xy 412.115 -8.0645) (xy 412.115 -7.6835) (xy 411.607 -7.6835)
				)
			)
		)
		(zone
			(layer "B.Cu")
			(hatch none 0.5)
			(connect_pads
				(clearance 0)
			)
			(min_thickness 0.25)
			(keepout
				(tracks allowed)
				(vias not_allowed)
				(pads allowed)
				(copperpour not_allowed)
				(footprints allowed)
			)
			(placement
				(enabled no)
				(sheetname "")
			)
			(fill
				(thermal_gap 0.5)
				(thermal_bridge_width 0.5)
				(island_removal_mode 0)
			)
			(polygon
				(pts
					(xy 411.607 -7.6835) (xy 412.115 -7.6835) (xy 412.115 -8.0645) (xy 411.607 -8.0645)
				)
			)
		)
	)
	(footprint ""
		(layer "B.Cu")
		(at 413.9438 -89.4207 -90)
		(property "Reference" "R3R10"
			(at 0 0 90)
			(layer "B.SilkS")
			(hide yes)
			(effects
				(font
					(size 1.27 1.27)
				)
				(justify mirror)
			)
		)
		(property "Value" ""
			(at 0 0 90)
			(layer "B.Fab")
			(effects
				(font
					(size 1.27 1.27)
				)
				(justify mirror)
			)
		)
		(duplicate_pad_numbers_are_jumpers no)
		(fp_poly
			(pts
				(xy 0.2794 -0.1016) (xy -0.2794 -0.1016) (xy -0.2794 0.9906) (xy 0.2794 0.9906)
			)
			(stroke
				(width 0)
				(type default)
			)
			(fill no)
			(layer "B.CrtYd")
		)
		(fp_line
			(start -0.2794 0.9906)
			(end -0.2794 -0.1016)
			(stroke
				(width 0.1)
				(type default)
			)
			(layer "B.Fab")
		)
		(fp_line
			(start 0.2794 0.9906)
			(end -0.2794 0.9906)
			(stroke
				(width 0.1)
				(type default)
			)
			(layer "B.Fab")
		)
		(fp_line
			(start -0.2794 -0.1016)
			(end 0.2794 -0.1016)
			(stroke
				(width 0.1)
				(type default)
			)
			(layer "B.Fab")
		)
		(fp_line
			(start 0.2794 -0.1016)
			(end 0.2794 0.9906)
			(stroke
				(width 0.1)
				(type default)
			)
			(layer "B.Fab")
		)
		(pad "1" smd rect
			(at 0 0 90)
			(size 0.508 0.508)
			(layers "B.Cu" "B.Mask" "B.Paste")
			(net "P3V3")
		)
		(pad "2" smd rect
			(at 0 0.889 90)
			(size 0.508 0.508)
			(layers "B.Cu" "B.Mask" "B.Paste")
			(net "H_CPU1_MEMGHJ_MEMHOT")
		)
		(zone
			(layer "B.Cu")
			(hatch none 0.5)
			(connect_pads
				(clearance 0)
			)
			(min_thickness 0.25)
			(keepout
				(tracks not_allowed)
				(vias allowed)
				(pads allowed)
				(copperpour not_allowed)
				(footprints allowed)
			)
			(placement
				(enabled no)
				(sheetname "")
			)
			(fill
				(thermal_gap 0.5)
				(thermal_bridge_width 0.5)
				(island_removal_mode 0)
			)
			(polygon
				(pts
					(xy 413.3088 -89.1667) (xy 413.3088 -89.6747) (xy 413.6898 -89.6747) (xy 413.6898 -89.1667)
				)
			)
		)
		(zone
			(layer "B.Cu")
			(hatch none 0.5)
			(connect_pads
				(clearance 0)
			)
			(min_thickness 0.25)
			(keepout
				(tracks allowed)
				(vias not_allowed)
				(pads allowed)
				(copperpour not_allowed)
				(footprints allowed)
			)
			(placement
				(enabled no)
				(sheetname "")
			)
			(fill
				(thermal_gap 0.5)
				(thermal_bridge_width 0.5)
				(island_removal_mode 0)
			)
			(polygon
				(pts
					(xy 413.6898 -89.1667) (xy 413.6898 -89.6747) (xy 413.3088 -89.6747) (xy 413.3088 -89.1667)
				)
			)
		)
	)
	(footprint ""
		(layer "B.Cu")
		(at 30.452568 -154.6352 90)
		(property "Reference" "C9L1"
			(at 0 0 90)
			(layer "B.SilkS")
			(hide yes)
			(effects
				(font
					(size 1.27 1.27)
				)
				(justify mirror)
			)
		)
		(property "Value" ""
			(at 0 0 90)
			(layer "B.Fab")
			(effects
				(font
					(size 1.27 1.27)
				)
				(justify mirror)
			)
		)
		(duplicate_pad_numbers_are_jumpers no)
		(fp_poly
			(pts
				(xy -0.3048 -0.1016) (xy -0.3048 0.9906) (xy 0.3048 0.9906) (xy 0.3048 -0.1016)
			)
			(stroke
				(width 0)
				(type default)
			)
			(fill no)
			(layer "B.CrtYd")
		)
		(fp_line
			(start 0.3048 -0.1016)
			(end 0.3048 0.9906)
			(stroke
				(width 0.1)
				(type default)
			)
			(layer "B.Fab")
		)
		(fp_line
			(start -0.3048 -0.1016)
			(end 0.3048 -0.1016)
			(stroke
				(width 0.1)
				(type default)
			)
			(layer "B.Fab")
		)
		(fp_line
			(start 0.3048 0.9906)
			(end -0.3048 0.9906)
			(stroke
				(width 0.1)
				(type default)
			)
			(layer "B.Fab")
		)
		(fp_line
			(start -0.3048 0.9906)
			(end -0.3048 -0.1016)
			(stroke
				(width 0.1)
				(type default)
			)
			(layer "B.Fab")
		)
		(pad "1" smd rect
			(at 0 0 270)
			(size 0.508 0.508)
			(layers "B.Cu" "B.Mask" "B.Paste")
			(net "M_M_VREF")
		)
		(pad "2" smd rect
			(at 0 0.889 270)
			(size 0.508 0.508)
			(layers "B.Cu" "B.Mask" "B.Paste")
			(net "GND")
		)
		(zone
			(layer "B.Cu")
			(hatch none 0.5)
			(connect_pads
				(clearance 0)
			)
			(min_thickness 0.25)
			(keepout
				(tracks allowed)
				(vias not_allowed)
				(pads allowed)
				(copperpour not_allowed)
				(footprints allowed)
			)
			(placement
				(enabled no)
				(sheetname "")
			)
			(fill
				(thermal_gap 0.5)
				(thermal_bridge_width 0.5)
				(island_removal_mode 0)
			)
			(polygon
				(pts
					(xy 30.706568 -154.8892) (xy 30.706568 -154.3812) (xy 31.087568 -154.3812) (xy 31.087568 -154.8892)
				)
			)
		)
		(zone
			(layer "B.Cu")
			(hatch none 0.5)
			(connect_pads
				(clearance 0)
			)
			(min_thickness 0.25)
			(keepout
				(tracks not_allowed)
				(vias allowed)
				(pads allowed)
				(copperpour not_allowed)
				(footprints allowed)
			)
			(placement
				(enabled no)
				(sheetname "")
			)
			(fill
				(thermal_gap 0.5)
				(thermal_bridge_width 0.5)
				(island_removal_mode 0)
			)
			(polygon
				(pts
					(xy 31.087568 -154.8892) (xy 31.087568 -154.3812) (xy 30.706568 -154.3812) (xy 30.706568 -154.8892)
				)
			)
		)
	)
	(footprint ""
		(layer "B.Cu")
		(at 330.116434 -62.456822 90)
		(property "Reference" "R3R7"
			(at 0 0 90)
			(layer "B.SilkS")
			(hide yes)
			(effects
				(font
					(size 1.27 1.27)
				)
				(justify mirror)
			)
		)
		(property "Value" ""
			(at 0 0 90)
			(layer "B.Fab")
			(effects
				(font
					(size 1.27 1.27)
				)
				(justify mirror)
			)
		)
		(duplicate_pad_numbers_are_jumpers no)
		(fp_poly
			(pts
				(xy 0.2794 -0.1016) (xy -0.2794 -0.1016) (xy -0.2794 0.9906) (xy 0.2794 0.9906)
			)
			(stroke
				(width 0)
				(type default)
			)
			(fill no)
			(layer "B.CrtYd")
		)
		(fp_line
			(start 0.2794 -0.1016)
			(end 0.2794 0.9906)
			(stroke
				(width 0.1)
				(type default)
			)
			(layer "B.Fab")
		)
		(fp_line
			(start -0.2794 -0.1016)
			(end 0.2794 -0.1016)
			(stroke
				(width 0.1)
				(type default)
			)
			(layer "B.Fab")
		)
		(fp_line
			(start 0.2794 0.9906)
			(end -0.2794 0.9906)
			(stroke
				(width 0.1)
				(type default)
			)
			(layer "B.Fab")
		)
		(fp_line
			(start -0.2794 0.9906)
			(end -0.2794 -0.1016)
			(stroke
				(width 0.1)
				(type default)
			)
			(layer "B.Fab")
		)
		(pad "1" smd rect
			(at 0 0 270)
			(size 0.508 0.508)
			(layers "B.Cu" "B.Mask" "B.Paste")
			(net "SMB_DDR_DEF_SCL_G_R")
		)
		(pad "2" smd rect
			(at 0 0.889 270)
			(size 0.508 0.508)
			(layers "B.Cu" "B.Mask" "B.Paste")
			(net "SMB_DDR_DEF_SCL_G")
		)
		(zone
			(layer "B.Cu")
			(hatch none 0.5)
			(connect_pads
				(clearance 0)
			)
			(min_thickness 0.25)
			(keepout
				(tracks allowed)
				(vias not_allowed)
				(pads allowed)
				(copperpour not_allowed)
				(footprints allowed)
			)
			(placement
				(enabled no)
				(sheetname "")
			)
			(fill
				(thermal_gap 0.5)
				(thermal_bridge_width 0.5)
				(island_removal_mode 0)
			)
			(polygon
				(pts
					(xy 330.370434 -62.710822) (xy 330.370434 -62.202822) (xy 330.751434 -62.202822) (xy 330.751434 -62.710822)
				)
			)
		)
		(zone
			(layer "B.Cu")
			(hatch none 0.5)
			(connect_pads
				(clearance 0)
			)
			(min_thickness 0.25)
			(keepout
				(tracks not_allowed)
				(vias allowed)
				(pads allowed)
				(copperpour not_allowed)
				(footprints allowed)
			)
			(placement
				(enabled no)
				(sheetname "")
			)
			(fill
				(thermal_gap 0.5)
				(thermal_bridge_width 0.5)
				(island_removal_mode 0)
			)
			(polygon
				(pts
					(xy 330.751434 -62.710822) (xy 330.751434 -62.202822) (xy 330.370434 -62.202822) (xy 330.370434 -62.710822)
				)
			)
		)
	)
)
